(kicad_pcb
	(version 20260206)
	(generator "pcbnew")
	(generator_version "10.0")
	(general
		(thickness 1.6)
		(legacy_teardrops no)
	)
	(paper "A4")
	(title_block
		(title "v1-chassis-manager — T6M_CM_d_v01_1031_1645.brd")
		(comment 1 "Open CloudServer (Microsoft) / footprints 1963-1972 of 2512")
	)
	(layers
		(0 "F.Cu" signal "TOP")
		(4 "In1.Cu" signal "GND1")
		(6 "In2.Cu" signal "IN1")
		(8 "In3.Cu" signal "VCC1")
		(10 "In4.Cu" signal "VCC2")
		(12 "In5.Cu" signal "GND2")
		(14 "In6.Cu" signal "IN2")
		(16 "In7.Cu" signal "IN3")
		(18 "In8.Cu" signal "GND3")
		(2 "B.Cu" signal "BOTTOM")
		(9 "F.Adhes" user "F.Adhesive")
		(11 "B.Adhes" user "B.Adhesive")
		(13 "F.Paste" user "Package Geometry/Pastemask Top")
		(15 "B.Paste" user "Package Geometry/Pastemask Bottom")
		(5 "F.SilkS" user "Ref Des/Silkscreen Top")
		(7 "B.SilkS" user "Ref Des/Silkscreen Bottom")
		(1 "F.Mask" user "Board Geometry/Soldermask Top")
		(3 "B.Mask" user "Board Geometry/Soldermask Bottom")
		(17 "Dwgs.User" user "User.Drawings")
		(19 "Cmts.User" user "User.Comments")
		(21 "Eco1.User" user "User.Eco1")
		(23 "Eco2.User" user "User.Eco2")
		(25 "Edge.Cuts" user "Board Geometry/Outline")
		(27 "Margin" user)
		(31 "F.CrtYd" user "Package Geometry/Place Bound Top")
		(29 "B.CrtYd" user "Package Geometry/Place Bound Bottom")
		(35 "F.Fab" user "Ref Des/Assembly Top")
		(33 "B.Fab" user "Ref Des/Assembly Bottom")
	)
	(footprint ""
		(layer "B.Cu")
		(at 165.210998 -155.38323 180)
		(property "Reference" "C472"
			(at 1.075182 -0.629158 0)
			(unlocked yes)
			(layer "B.SilkS")
			(effects
				(font
					(size 0.7874 0.5842)
					(thickness 0.1524)
				)
				(justify left mirror)
			)
		)
		(property "Value" ""
			(at 0 0 0)
			(layer "B.Fab")
			(effects
				(font
					(size 1.27 1.27)
				)
				(justify mirror)
			)
		)
		(duplicate_pad_numbers_are_jumpers no)
		(fp_line
			(start 0.7874 0.4064)
			(end 0.7874 -0.4064)
			(stroke
				(width 0.1524)
				(type default)
			)
			(layer "B.SilkS")
		)
		(fp_line
			(start 0.7874 -0.4064)
			(end -0.7874 -0.4064)
			(stroke
				(width 0.1524)
				(type default)
			)
			(layer "B.SilkS")
		)
		(fp_line
			(start 0 0.381)
			(end 0 -0.381)
			(stroke
				(width 0.1524)
				(type default)
			)
			(layer "B.SilkS")
		)
		(fp_line
			(start -0.7874 0.4064)
			(end 0.7874 0.4064)
			(stroke
				(width 0.1524)
				(type default)
			)
			(layer "B.SilkS")
		)
		(fp_line
			(start -0.7874 -0.4064)
			(end -0.7874 0.4064)
			(stroke
				(width 0.1524)
				(type default)
			)
			(layer "B.SilkS")
		)
		(fp_poly
			(pts
				(xy 0.5334 0.254) (xy 0.635 0.254) (xy 0.635 0.2286) (xy 0.635 -0.254) (xy 0.5334 -0.254) (xy 0.5334 -0.2794)
				(xy -0.5334 -0.2794) (xy -0.5334 -0.254) (xy -0.635 -0.254) (xy -0.635 0.254) (xy -0.5334 0.254)
				(xy -0.5334 0.2794) (xy 0.508 0.2794) (xy 0.5334 0.2794)
			)
			(stroke
				(width 0)
				(type default)
			)
			(fill no)
			(layer "B.CrtYd")
		)
		(pad "1" smd rect
			(at -0.40005 0)
			(size 0.4572 0.508)
			(layers "B.Cu" "B.Mask" "B.Paste")
			(net "P1V9_LAN2")
		)
		(pad "2" smd rect
			(at 0.40005 0)
			(size 0.4572 0.508)
			(layers "B.Cu" "B.Mask" "B.Paste")
			(net "GND")
		)
	)
	(footprint ""
		(layer "B.Cu")
		(at 129.778252 -136.74471 90)
		(property "Reference" "C192"
			(at -5.94741 0.25019 270)
			(unlocked yes)
			(layer "B.SilkS")
			(effects
				(font
					(size 0.7874 0.5842)
					(thickness 0.1524)
				)
				(justify left mirror)
			)
		)
		(property "Value" ""
			(at 0 0 90)
			(layer "B.Fab")
			(effects
				(font
					(size 1.27 1.27)
				)
				(justify mirror)
			)
		)
		(duplicate_pad_numbers_are_jumpers no)
		(fp_line
			(start 0.7874 -0.4064)
			(end -0.7874 -0.4064)
			(stroke
				(width 0.1524)
				(type default)
			)
			(layer "B.SilkS")
		)
		(fp_line
			(start -0.7874 -0.4064)
			(end -0.7874 0.4064)
			(stroke
				(width 0.1524)
				(type default)
			)
			(layer "B.SilkS")
		)
		(fp_line
			(start 0 0.381)
			(end 0 -0.381)
			(stroke
				(width 0.1524)
				(type default)
			)
			(layer "B.SilkS")
		)
		(fp_line
			(start 0.7874 0.4064)
			(end 0.7874 -0.4064)
			(stroke
				(width 0.1524)
				(type default)
			)
			(layer "B.SilkS")
		)
		(fp_line
			(start -0.7874 0.4064)
			(end 0.7874 0.4064)
			(stroke
				(width 0.1524)
				(type default)
			)
			(layer "B.SilkS")
		)
		(fp_poly
			(pts
				(xy 0.5334 0.254) (xy 0.635 0.254) (xy 0.635 0.2286) (xy 0.635 -0.254) (xy 0.5334 -0.254) (xy 0.5334 -0.2794)
				(xy -0.5334 -0.2794) (xy -0.5334 -0.254) (xy -0.635 -0.254) (xy -0.635 0.254) (xy -0.5334 0.254)
				(xy -0.5334 0.2794) (xy 0.508 0.2794) (xy 0.5334 0.2794)
			)
			(stroke
				(width 0)
				(type default)
			)
			(fill no)
			(layer "B.CrtYd")
		)
		(pad "1" smd rect
			(at -0.40005 0 270)
			(size 0.4572 0.508)
			(layers "B.Cu" "B.Mask" "B.Paste")
			(net "CLK_100M_PCIE_SW_NODE1_DP")
		)
		(pad "2" smd rect
			(at 0.40005 0 270)
			(size 0.4572 0.508)
			(layers "B.Cu" "B.Mask" "B.Paste")
			(net "CLK_100M_PCIE_SW_NODE1_C_DP")
		)
	)
	(footprint ""
		(layer "B.Cu")
		(at 62.19317 -135.072374)
		(property "Reference" "C272"
			(at -40.645588 52.933346 0)
			(unlocked yes)
			(layer "B.SilkS")
			(effects
				(font
					(size 0.7874 0.5842)
					(thickness 0.1524)
				)
				(justify left mirror)
			)
		)
		(property "Value" ""
			(at 0 0 0)
			(layer "B.Fab")
			(effects
				(font
					(size 1.27 1.27)
				)
				(justify mirror)
			)
		)
		(duplicate_pad_numbers_are_jumpers no)
		(fp_line
			(start -0.7874 -0.4064)
			(end -0.7874 0.4064)
			(stroke
				(width 0.1524)
				(type default)
			)
			(layer "B.SilkS")
		)
		(fp_line
			(start -0.7874 0.4064)
			(end 0.7874 0.4064)
			(stroke
				(width 0.1524)
				(type default)
			)
			(layer "B.SilkS")
		)
		(fp_line
			(start 0 0.381)
			(end 0 -0.381)
			(stroke
				(width 0.1524)
				(type default)
			)
			(layer "B.SilkS")
		)
		(fp_line
			(start 0.7874 -0.4064)
			(end -0.7874 -0.4064)
			(stroke
				(width 0.1524)
				(type default)
			)
			(layer "B.SilkS")
		)
		(fp_line
			(start 0.7874 0.4064)
			(end 0.7874 -0.4064)
			(stroke
				(width 0.1524)
				(type default)
			)
			(layer "B.SilkS")
		)
		(fp_poly
			(pts
				(xy 0.5334 0.254) (xy 0.635 0.254) (xy 0.635 0.2286) (xy 0.635 -0.254) (xy 0.5334 -0.254) (xy 0.5334 -0.2794)
				(xy -0.5334 -0.2794) (xy -0.5334 -0.254) (xy -0.635 -0.254) (xy -0.635 0.254) (xy -0.5334 0.254)
				(xy -0.5334 0.2794) (xy 0.508 0.2794) (xy 0.5334 0.2794)
			)
			(stroke
				(width 0)
				(type default)
			)
			(fill no)
			(layer "B.CrtYd")
		)
		(pad "1" smd rect
			(at -0.40005 0 180)
			(size 0.4572 0.508)
			(layers "B.Cu" "B.Mask" "B.Paste")
			(net "P1V538_BMC_NODE1")
		)
		(pad "2" smd rect
			(at 0.40005 0 180)
			(size 0.4572 0.508)
			(layers "B.Cu" "B.Mask" "B.Paste")
			(net "GND")
		)
	)
	(footprint ""
		(layer "B.Cu")
		(at 159.02178 -157.744922 -90)
		(property "Reference" "C462"
			(at -0.347218 1.448054 270)
			(unlocked yes)
			(layer "B.SilkS")
			(effects
				(font
					(size 0.7874 0.5842)
					(thickness 0.1524)
				)
				(justify left mirror)
			)
		)
		(property "Value" ""
			(at 0 0 90)
			(layer "B.Fab")
			(effects
				(font
					(size 1.27 1.27)
				)
				(justify mirror)
			)
		)
		(duplicate_pad_numbers_are_jumpers no)
		(fp_line
			(start -0.7874 0.4064)
			(end 0.7874 0.4064)
			(stroke
				(width 0.1524)
				(type default)
			)
			(layer "B.SilkS")
		)
		(fp_line
			(start 0.7874 0.4064)
			(end 0.7874 -0.4064)
			(stroke
				(width 0.1524)
				(type default)
			)
			(layer "B.SilkS")
		)
		(fp_line
			(start 0 0.381)
			(end 0 -0.381)
			(stroke
				(width 0.1524)
				(type default)
			)
			(layer "B.SilkS")
		)
		(fp_line
			(start -0.7874 -0.4064)
			(end -0.7874 0.4064)
			(stroke
				(width 0.1524)
				(type default)
			)
			(layer "B.SilkS")
		)
		(fp_line
			(start 0.7874 -0.4064)
			(end -0.7874 -0.4064)
			(stroke
				(width 0.1524)
				(type default)
			)
			(layer "B.SilkS")
		)
		(fp_poly
			(pts
				(xy 0.5334 0.254) (xy 0.635 0.254) (xy 0.635 0.2286) (xy 0.635 -0.254) (xy 0.5334 -0.254) (xy 0.5334 -0.2794)
				(xy -0.5334 -0.2794) (xy -0.5334 -0.254) (xy -0.635 -0.254) (xy -0.635 0.254) (xy -0.5334 0.254)
				(xy -0.5334 0.2794) (xy 0.508 0.2794) (xy 0.5334 0.2794)
			)
			(stroke
				(width 0)
				(type default)
			)
			(fill no)
			(layer "B.CrtYd")
		)
		(pad "1" smd rect
			(at -0.40005 0 90)
			(size 0.4572 0.508)
			(layers "B.Cu" "B.Mask" "B.Paste")
			(net "P1V05_LAN2")
		)
		(pad "2" smd rect
			(at 0.40005 0 90)
			(size 0.4572 0.508)
			(layers "B.Cu" "B.Mask" "B.Paste")
			(net "GND")
		)
	)
	(footprint ""
		(layer "B.Cu")
		(at 87.90813 -76.678282 180)
		(property "Reference" "R141"
			(at 2.202942 -9.69518 0)
			(unlocked yes)
			(layer "B.SilkS")
			(effects
				(font
					(size 0.7874 0.5842)
					(thickness 0.1524)
				)
				(justify left mirror)
			)
		)
		(property "Value" ""
			(at 0 0 0)
			(layer "B.Fab")
			(effects
				(font
					(size 1.27 1.27)
				)
				(justify mirror)
			)
		)
		(duplicate_pad_numbers_are_jumpers no)
		(fp_line
			(start 0.7874 0.4064)
			(end 0.7874 -0.4064)
			(stroke
				(width 0.1524)
				(type default)
			)
			(layer "B.SilkS")
		)
		(fp_line
			(start 0.7874 -0.4064)
			(end -0.7874 -0.4064)
			(stroke
				(width 0.1524)
				(type default)
			)
			(layer "B.SilkS")
		)
		(fp_line
			(start -0.7874 0.4064)
			(end 0.7874 0.4064)
			(stroke
				(width 0.1524)
				(type default)
			)
			(layer "B.SilkS")
		)
		(fp_line
			(start -0.7874 -0.4064)
			(end -0.7874 0.4064)
			(stroke
				(width 0.1524)
				(type default)
			)
			(layer "B.SilkS")
		)
		(fp_poly
			(pts
				(xy 0.508 0.2794) (xy 0.508 0.2286) (xy 0.635 0.2286) (xy 0.635 -0.254) (xy 0.5334 -0.254) (xy 0.5334 -0.2794)
				(xy -0.5334 -0.2794) (xy -0.5334 -0.254) (xy -0.635 -0.254) (xy -0.635 0.254) (xy -0.5334 0.254)
				(xy -0.5334 0.2794)
			)
			(stroke
				(width 0)
				(type default)
			)
			(fill no)
			(layer "B.CrtYd")
		)
		(pad "1" smd rect
			(at -0.40005 0)
			(size 0.4572 0.508)
			(layers "B.Cu" "B.Mask" "B.Paste")
			(net "GND")
		)
		(pad "2" smd rect
			(at 0.40005 0)
			(size 0.4572 0.508)
			(layers "B.Cu" "B.Mask" "B.Paste")
			(net "PWRGD_CPU_NODE1_EPWRGOOD")
		)
	)
	(footprint ""
		(layer "B.Cu")
		(at 90.81262 -164.878512)
		(property "Reference" "R787"
			(at 24.774144 20.136104 0)
			(unlocked yes)
			(layer "B.SilkS")
			(effects
				(font
					(size 0.7874 0.5842)
					(thickness 0.1524)
				)
				(justify left mirror)
			)
		)
		(property "Value" ""
			(at 0 0 0)
			(layer "B.Fab")
			(effects
				(font
					(size 1.27 1.27)
				)
				(justify mirror)
			)
		)
		(duplicate_pad_numbers_are_jumpers no)
		(fp_line
			(start -0.7874 -0.4064)
			(end -0.7874 0.4064)
			(stroke
				(width 0.1524)
				(type default)
			)
			(layer "B.SilkS")
		)
		(fp_line
			(start -0.7874 0.4064)
			(end 0.7874 0.4064)
			(stroke
				(width 0.1524)
				(type default)
			)
			(layer "B.SilkS")
		)
		(fp_line
			(start 0.7874 -0.4064)
			(end -0.7874 -0.4064)
			(stroke
				(width 0.1524)
				(type default)
			)
			(layer "B.SilkS")
		)
		(fp_line
			(start 0.7874 0.4064)
			(end 0.7874 -0.4064)
			(stroke
				(width 0.1524)
				(type default)
			)
			(layer "B.SilkS")
		)
		(fp_poly
			(pts
				(xy 0.508 0.2794) (xy 0.508 0.2286) (xy 0.635 0.2286) (xy 0.635 -0.254) (xy 0.5334 -0.254) (xy 0.5334 -0.2794)
				(xy -0.5334 -0.2794) (xy -0.5334 -0.254) (xy -0.635 -0.254) (xy -0.635 0.254) (xy -0.5334 0.254)
				(xy -0.5334 0.2794)
			)
			(stroke
				(width 0)
				(type default)
			)
			(fill no)
			(layer "B.CrtYd")
		)
		(pad "1" smd rect
			(at -0.40005 0 180)
			(size 0.4572 0.508)
			(layers "B.Cu" "B.Mask" "B.Paste")
			(net "UART_SW_S3_N")
		)
		(pad "2" smd rect
			(at 0.40005 0 180)
			(size 0.4572 0.508)
			(layers "B.Cu" "B.Mask" "B.Paste")
			(net "P3V3_NODE1")
		)
	)
	(footprint ""
		(layer "B.Cu")
		(at 71.99376 -188.126624 -90)
		(property "Reference" "C680"
			(at -4.318254 0.33401 270)
			(unlocked yes)
			(layer "B.SilkS")
			(effects
				(font
					(size 0.7874 0.5842)
					(thickness 0.1524)
				)
				(justify left mirror)
			)
		)
		(property "Value" ""
			(at 0 0 90)
			(layer "B.Fab")
			(effects
				(font
					(size 1.27 1.27)
				)
				(justify mirror)
			)
		)
		(duplicate_pad_numbers_are_jumpers no)
		(fp_line
			(start -0.7874 0.4064)
			(end 0.7874 0.4064)
			(stroke
				(width 0.1524)
				(type default)
			)
			(layer "B.SilkS")
		)
		(fp_line
			(start 0.7874 0.4064)
			(end 0.7874 -0.4064)
			(stroke
				(width 0.1524)
				(type default)
			)
			(layer "B.SilkS")
		)
		(fp_line
			(start 0 0.381)
			(end 0 -0.381)
			(stroke
				(width 0.1524)
				(type default)
			)
			(layer "B.SilkS")
		)
		(fp_line
			(start -0.7874 -0.4064)
			(end -0.7874 0.4064)
			(stroke
				(width 0.1524)
				(type default)
			)
			(layer "B.SilkS")
		)
		(fp_line
			(start 0.7874 -0.4064)
			(end -0.7874 -0.4064)
			(stroke
				(width 0.1524)
				(type default)
			)
			(layer "B.SilkS")
		)
		(fp_poly
			(pts
				(xy 0.5334 0.254) (xy 0.635 0.254) (xy 0.635 0.2286) (xy 0.635 -0.254) (xy 0.5334 -0.254) (xy 0.5334 -0.2794)
				(xy -0.5334 -0.2794) (xy -0.5334 -0.254) (xy -0.635 -0.254) (xy -0.635 0.254) (xy -0.5334 0.254)
				(xy -0.5334 0.2794) (xy 0.508 0.2794) (xy 0.5334 0.2794)
			)
			(stroke
				(width 0)
				(type default)
			)
			(fill no)
			(layer "B.CrtYd")
		)
		(pad "1" smd rect
			(at -0.40005 0 90)
			(size 0.4572 0.508)
			(layers "B.Cu" "B.Mask" "B.Paste")
			(net "UART_T3_NODE2_TXD_R")
		)
		(pad "2" smd rect
			(at 0.40005 0 90)
			(size 0.4572 0.508)
			(layers "B.Cu" "B.Mask" "B.Paste")
			(net "GND")
		)
	)
	(footprint ""
		(layer "B.Cu")
		(at 118.47576 -185.205624 90)
		(property "Reference" "R875"
			(at 3.957828 0.383794 270)
			(unlocked yes)
			(layer "B.SilkS")
			(effects
				(font
					(size 0.7874 0.5842)
					(thickness 0.1524)
				)
				(justify left mirror)
			)
		)
		(property "Value" ""
			(at 0 0 90)
			(layer "B.Fab")
			(effects
				(font
					(size 1.27 1.27)
				)
				(justify mirror)
			)
		)
		(duplicate_pad_numbers_are_jumpers no)
		(fp_line
			(start 0.7874 -0.4064)
			(end -0.7874 -0.4064)
			(stroke
				(width 0.1524)
				(type default)
			)
			(layer "B.SilkS")
		)
		(fp_line
			(start -0.7874 -0.4064)
			(end -0.7874 0.4064)
			(stroke
				(width 0.1524)
				(type default)
			)
			(layer "B.SilkS")
		)
		(fp_line
			(start 0.7874 0.4064)
			(end 0.7874 -0.4064)
			(stroke
				(width 0.1524)
				(type default)
			)
			(layer "B.SilkS")
		)
		(fp_line
			(start -0.7874 0.4064)
			(end 0.7874 0.4064)
			(stroke
				(width 0.1524)
				(type default)
			)
			(layer "B.SilkS")
		)
		(fp_poly
			(pts
				(xy 0.508 0.2794) (xy 0.508 0.2286) (xy 0.635 0.2286) (xy 0.635 -0.254) (xy 0.5334 -0.254) (xy 0.5334 -0.2794)
				(xy -0.5334 -0.2794) (xy -0.5334 -0.254) (xy -0.635 -0.254) (xy -0.635 0.254) (xy -0.5334 0.254)
				(xy -0.5334 0.2794)
			)
			(stroke
				(width 0)
				(type default)
			)
			(fill no)
			(layer "B.CrtYd")
		)
		(pad "1" smd rect
			(at -0.40005 0 270)
			(size 0.4572 0.508)
			(layers "B.Cu" "B.Mask" "B.Paste")
			(net "T7_NODE2_EN")
		)
		(pad "2" smd rect
			(at 0.40005 0 270)
			(size 0.4572 0.508)
			(layers "B.Cu" "B.Mask" "B.Paste")
			(net "T7_NODE2_EN_R")
		)
	)
	(footprint ""
		(layer "B.Cu")
		(at 142.07236 -171.997624 180)
		(property "Reference" "R729"
			(at 1.275588 0.274828 0)
			(unlocked yes)
			(layer "B.SilkS")
			(effects
				(font
					(size 0.7874 0.5842)
					(thickness 0.1524)
				)
				(justify left mirror)
			)
		)
		(property "Value" ""
			(at 0 0 0)
			(layer "B.Fab")
			(effects
				(font
					(size 1.27 1.27)
				)
				(justify mirror)
			)
		)
		(duplicate_pad_numbers_are_jumpers no)
		(fp_line
			(start 0.7874 0.4064)
			(end 0.7874 -0.4064)
			(stroke
				(width 0.1524)
				(type default)
			)
			(layer "B.SilkS")
		)
		(fp_line
			(start 0.7874 -0.4064)
			(end -0.7874 -0.4064)
			(stroke
				(width 0.1524)
				(type default)
			)
			(layer "B.SilkS")
		)
		(fp_line
			(start -0.7874 0.4064)
			(end 0.7874 0.4064)
			(stroke
				(width 0.1524)
				(type default)
			)
			(layer "B.SilkS")
		)
		(fp_line
			(start -0.7874 -0.4064)
			(end -0.7874 0.4064)
			(stroke
				(width 0.1524)
				(type default)
			)
			(layer "B.SilkS")
		)
		(fp_poly
			(pts
				(xy 0.508 0.2794) (xy 0.508 0.2286) (xy 0.635 0.2286) (xy 0.635 -0.254) (xy 0.5334 -0.254) (xy 0.5334 -0.2794)
				(xy -0.5334 -0.2794) (xy -0.5334 -0.254) (xy -0.635 -0.254) (xy -0.635 0.254) (xy -0.5334 0.254)
				(xy -0.5334 0.2794)
			)
			(stroke
				(width 0)
				(type default)
			)
			(fill no)
			(layer "B.CrtYd")
		)
		(pad "1" smd rect
			(at -0.40005 0)
			(size 0.4572 0.508)
			(layers "B.Cu" "B.Mask" "B.Paste")
			(net "T9_NODE2_EN")
		)
		(pad "2" smd rect
			(at 0.40005 0)
			(size 0.4572 0.508)
			(layers "B.Cu" "B.Mask" "B.Paste")
			(net "P5V_NODE1")
		)
	)
	(footprint ""
		(layer "B.Cu")
		(at 45.669454 -97.078038 -90)
		(property "Reference" "R133"
			(at -1.042162 -1.014476 270)
			(unlocked yes)
			(layer "B.SilkS")
			(effects
				(font
					(size 0.7874 0.5842)
					(thickness 0.1524)
				)
				(justify left mirror)
			)
		)
		(property "Value" ""
			(at 0 0 90)
			(layer "B.Fab")
			(effects
				(font
					(size 1.27 1.27)
				)
				(justify mirror)
			)
		)
		(duplicate_pad_numbers_are_jumpers no)
		(fp_line
			(start -0.7874 0.4064)
			(end 0.7874 0.4064)
			(stroke
				(width 0.1524)
				(type default)
			)
			(layer "B.SilkS")
		)
		(fp_line
			(start 0.7874 0.4064)
			(end 0.7874 -0.4064)
			(stroke
				(width 0.1524)
				(type default)
			)
			(layer "B.SilkS")
		)
		(fp_line
			(start -0.7874 -0.4064)
			(end -0.7874 0.4064)
			(stroke
				(width 0.1524)
				(type default)
			)
			(layer "B.SilkS")
		)
		(fp_line
			(start 0.7874 -0.4064)
			(end -0.7874 -0.4064)
			(stroke
				(width 0.1524)
				(type default)
			)
			(layer "B.SilkS")
		)
		(fp_poly
			(pts
				(xy 0.508 0.2794) (xy 0.508 0.2286) (xy 0.635 0.2286) (xy 0.635 -0.254) (xy 0.5334 -0.254) (xy 0.5334 -0.2794)
				(xy -0.5334 -0.2794) (xy -0.5334 -0.254) (xy -0.635 -0.254) (xy -0.635 0.254) (xy -0.5334 0.254)
				(xy -0.5334 0.2794)
			)
			(stroke
				(width 0)
				(type default)
			)
			(fill no)
			(layer "B.CrtYd")
		)
		(pad "1" smd rect
			(at -0.40005 0 90)
			(size 0.4572 0.508)
			(layers "B.Cu" "B.Mask" "B.Paste")
			(net "P3V3_NODE1")
		)
		(pad "2" smd rect
			(at 0.40005 0 90)
			(size 0.4572 0.508)
			(layers "B.Cu" "B.Mask" "B.Paste")
			(net "SMB_CPU_NODE1_BMC_DAT")
		)
	)
)
